# BASEBOARD_FAB2 (Tioga Pass) — schematic netlist excerpt (pin names and nets, part order shuffled) for the footprints in the layout excerpt that follows; sources: Cadence DE-HDL packaged netlist, KiCad conversion of Wiwynn_Tioga_Pass_MB.brd

C1U22  CAP_A  0.1UF 16V 10% X7R  pkg 0402V  page 152 : A = P0V7_GTL2014_2 ; B = GND
C8M9  CAP_A  47UF 4V 20% X5R  pkg 0603V  page 228 : A = PVDDQ_KLM ; B = GND
C3P29  CAP  0.22UF 16V 10% X7R  pkg 0402  page 107 : A = P3E_CPU0_PE1_SS_TXN<4> ; B = P3E_CPU0_PE1_SS_C_TXN<4>

(kicad_pcb
	(version 20260206)
	(generator "pcbnew")
	(generator_version "10.0")
	(general
		(thickness 1.6)
		(legacy_teardrops no)
	)
	(paper "A4")
	(title_block
		(title "Wiwynn_Tioga_Pass_MB.brd")
		(comment 1 "Tioga Pass / footprints 3200-3202 of 4770")
	)
	(layers
		(0 "F.Cu" signal "TOP")
		(4 "In1.Cu" signal "L2GND")
		(6 "In2.Cu" signal "L3")
		(8 "In3.Cu" signal "L4GND")
		(10 "In4.Cu" signal "L5")
		(12 "In5.Cu" signal "L6GND")
		(14 "In6.Cu" signal "L7VCC")
		(16 "In7.Cu" signal "L8VCC")
		(18 "In8.Cu" signal "L9GND")
		(20 "In9.Cu" signal "L10")
		(22 "In10.Cu" signal "L11GND")
		(24 "In11.Cu" signal "L12")
		(26 "In12.Cu" signal "L13GND")
		(2 "B.Cu" signal "BOTTOM")
		(9 "F.Adhes" user "F.Adhesive")
		(11 "B.Adhes" user "B.Adhesive")
		(13 "F.Paste" user "Package Geometry/Pastemask Top")
		(15 "B.Paste" user "Package Geometry/Pastemask Bottom")
		(5 "F.SilkS" user "Ref Des/Silkscreen Top")
		(7 "B.SilkS" user "Ref Des/Silkscreen Bottom")
		(1 "F.Mask" user "Board Geometry/Soldermask Top")
		(3 "B.Mask" user "Board Geometry/Soldermask Bottom")
		(17 "Dwgs.User" user "User.Drawings")
		(19 "Cmts.User" user "User.Comments")
		(21 "Eco1.User" user "User.Eco1")
		(23 "Eco2.User" user "User.Eco2")
		(25 "Edge.Cuts" user "Board Geometry/Outline")
		(27 "Margin" user)
		(31 "F.CrtYd" user "Package Geometry/Place Bound Top")
		(29 "B.CrtYd" user "Package Geometry/Place Bound Bottom")
		(35 "F.Fab" user "Ref Des/Assembly Top")
		(33 "B.Fab" user "Ref Des/Assembly Bottom")
	)
	(footprint ""
		(layer "B.Cu")
		(at 351.421192 -77.834236)
		(property "Reference" "C3P29"
			(at 0 0 0)
			(layer "B.SilkS")
			(hide yes)
			(effects
				(font
					(size 1.27 1.27)
				)
				(justify mirror)
			)
		)
		(property "Value" ""
			(at 0 0 0)
			(layer "B.Fab")
			(effects
				(font
					(size 1.27 1.27)
				)
				(justify mirror)
			)
		)
		(duplicate_pad_numbers_are_jumpers no)
		(fp_poly
			(pts
				(xy -0.3048 -0.1016) (xy -0.3048 0.9906) (xy 0.3048 0.9906) (xy 0.3048 -0.1016)
			)
			(stroke
				(width 0)
				(type default)
			)
			(fill no)
			(layer "B.CrtYd")
		)
		(fp_line
			(start -0.3048 -0.1016)
			(end 0.3048 -0.1016)
			(stroke
				(width 0.1)
				(type default)
			)
			(layer "B.Fab")
		)
		(fp_line
			(start -0.3048 0.9906)
			(end -0.3048 -0.1016)
			(stroke
				(width 0.1)
				(type default)
			)
			(layer "B.Fab")
		)
		(fp_line
			(start 0.3048 -0.1016)
			(end 0.3048 0.9906)
			(stroke
				(width 0.1)
				(type default)
			)
			(layer "B.Fab")
		)
		(fp_line
			(start 0.3048 0.9906)
			(end -0.3048 0.9906)
			(stroke
				(width 0.1)
				(type default)
			)
			(layer "B.Fab")
		)
		(pad "1" smd rect
			(at 0 0 180)
			(size 0.508 0.508)
			(layers "B.Cu" "B.Mask" "B.Paste")
			(net "P3E_CPU0_PE1_SS_TXN<4>")
		)
		(pad "2" smd rect
			(at 0 0.889 180)
			(size 0.508 0.508)
			(layers "B.Cu" "B.Mask" "B.Paste")
			(net "P3E_CPU0_PE1_SS_C_TXN<4>")
		)
		(zone
			(layer "B.Cu")
			(hatch none 0.5)
			(connect_pads
				(clearance 0)
			)
			(min_thickness 0.25)
			(keepout
				(tracks allowed)
				(vias not_allowed)
				(pads allowed)
				(copperpour not_allowed)
				(footprints allowed)
			)
			(placement
				(enabled no)
				(sheetname "")
			)
			(fill
				(thermal_gap 0.5)
				(thermal_bridge_width 0.5)
				(island_removal_mode 0)
			)
			(polygon
				(pts
					(xy 351.675192 -77.580236) (xy 351.167192 -77.580236) (xy 351.167192 -77.199236) (xy 351.675192 -77.199236)
				)
			)
		)
		(zone
			(layer "B.Cu")
			(hatch none 0.5)
			(connect_pads
				(clearance 0)
			)
			(min_thickness 0.25)
			(keepout
				(tracks not_allowed)
				(vias allowed)
				(pads allowed)
				(copperpour not_allowed)
				(footprints allowed)
			)
			(placement
				(enabled no)
				(sheetname "")
			)
			(fill
				(thermal_gap 0.5)
				(thermal_bridge_width 0.5)
				(island_removal_mode 0)
			)
			(polygon
				(pts
					(xy 351.675192 -77.199236) (xy 351.167192 -77.199236) (xy 351.167192 -77.580236) (xy 351.675192 -77.580236)
				)
			)
		)
	)
	(footprint ""
		(layer "B.Cu")
		(at 441.833 -13.8938 90)
		(property "Reference" "C1U22"
			(at 0 0 90)
			(layer "B.SilkS")
			(hide yes)
			(effects
				(font
					(size 1.27 1.27)
				)
				(justify mirror)
			)
		)
		(property "Value" ""
			(at 0 0 90)
			(layer "B.Fab")
			(effects
				(font
					(size 1.27 1.27)
				)
				(justify mirror)
			)
		)
		(duplicate_pad_numbers_are_jumpers no)
		(fp_poly
			(pts
				(xy -0.3048 -0.1016) (xy -0.3048 0.9906) (xy 0.3048 0.9906) (xy 0.3048 -0.1016)
			)
			(stroke
				(width 0)
				(type default)
			)
			(fill no)
			(layer "B.CrtYd")
		)
		(fp_line
			(start 0.3048 -0.1016)
			(end 0.3048 0.9906)
			(stroke
				(width 0.1)
				(type default)
			)
			(layer "B.Fab")
		)
		(fp_line
			(start -0.3048 -0.1016)
			(end 0.3048 -0.1016)
			(stroke
				(width 0.1)
				(type default)
			)
			(layer "B.Fab")
		)
		(fp_line
			(start 0.3048 0.9906)
			(end -0.3048 0.9906)
			(stroke
				(width 0.1)
				(type default)
			)
			(layer "B.Fab")
		)
		(fp_line
			(start -0.3048 0.9906)
			(end -0.3048 -0.1016)
			(stroke
				(width 0.1)
				(type default)
			)
			(layer "B.Fab")
		)
		(pad "1" smd rect
			(at 0 0 270)
			(size 0.508 0.508)
			(layers "B.Cu" "B.Mask" "B.Paste")
			(net "P0V7_GTL2014_2")
		)
		(pad "2" smd rect
			(at 0 0.889 270)
			(size 0.508 0.508)
			(layers "B.Cu" "B.Mask" "B.Paste")
			(net "GND")
		)
		(zone
			(layer "B.Cu")
			(hatch none 0.5)
			(connect_pads
				(clearance 0)
			)
			(min_thickness 0.25)
			(keepout
				(tracks allowed)
				(vias not_allowed)
				(pads allowed)
				(copperpour not_allowed)
				(footprints allowed)
			)
			(placement
				(enabled no)
				(sheetname "")
			)
			(fill
				(thermal_gap 0.5)
				(thermal_bridge_width 0.5)
				(island_removal_mode 0)
			)
			(polygon
				(pts
					(xy 442.087 -14.1478) (xy 442.087 -13.6398) (xy 442.468 -13.6398) (xy 442.468 -14.1478)
				)
			)
		)
		(zone
			(layer "B.Cu")
			(hatch none 0.5)
			(connect_pads
				(clearance 0)
			)
			(min_thickness 0.25)
			(keepout
				(tracks not_allowed)
				(vias allowed)
				(pads allowed)
				(copperpour not_allowed)
				(footprints allowed)
			)
			(placement
				(enabled no)
				(sheetname "")
			)
			(fill
				(thermal_gap 0.5)
				(thermal_bridge_width 0.5)
				(island_removal_mode 0)
			)
			(polygon
				(pts
					(xy 442.468 -14.1478) (xy 442.468 -13.6398) (xy 442.087 -13.6398) (xy 442.087 -14.1478)
				)
			)
		)
	)
	(footprint ""
		(layer "B.Cu")
		(at 79.550768 -125.8824 -90)
		(property "Reference" "C8M9"
			(at 1.75387 0.874268 0)
			(unlocked yes)
			(layer "B.SilkS")
			(effects
				(font
					(size 0.7874 0.5842)
					(thickness 0.1524)
				)
				(justify mirror)
			)
		)
		(property "Value" ""
			(at 0 0 90)
			(layer "B.Fab")
			(effects
				(font
					(size 1.27 1.27)
				)
				(justify mirror)
			)
		)
		(duplicate_pad_numbers_are_jumpers no)
		(fp_rect
			(start 0.500126 1.598422)
			(end -0.500126 -0.201422)
			(stroke
				(width 0)
				(type default)
			)
			(fill no)
			(layer "B.CrtYd")
		)
		(fp_line
			(start -0.500126 1.598422)
			(end 0.500126 1.598422)
			(stroke
				(width 0.1)
				(type default)
			)
			(layer "B.Fab")
		)
		(fp_line
			(start 0.500126 1.598422)
			(end 0.500126 -0.201422)
			(stroke
				(width 0.1)
				(type default)
			)
			(layer "B.Fab")
		)
		(fp_line
			(start -0.500126 -0.201422)
			(end -0.500126 1.598422)
			(stroke
				(width 0.1)
				(type default)
			)
			(layer "B.Fab")
		)
		(fp_line
			(start 0.500126 -0.201422)
			(end -0.500126 -0.201422)
			(stroke
				(width 0.1)
				(type default)
			)
			(layer "B.Fab")
		)
		(pad "1" smd rect
			(at 0 0 180)
			(size 0.889 0.9906)
			(layers "B.Cu" "B.Mask" "B.Paste")
			(net "PVDDQ_KLM")
		)
		(pad "2" smd rect
			(at 0 1.397 180)
			(size 0.889 0.9906)
			(layers "B.Cu" "B.Mask" "B.Paste")
			(net "GND")
		)
		(zone
			(layer "B.Cu")
			(hatch none 0.5)
			(connect_pads
				(clearance 0)
			)
			(min_thickness 0.25)
			(keepout
				(tracks not_allowed)
				(vias allowed)
				(pads allowed)
				(copperpour not_allowed)
				(footprints allowed)
			)
			(placement
				(enabled no)
				(sheetname "")
			)
			(fill
				(thermal_gap 0.5)
				(thermal_bridge_width 0.5)
				(island_removal_mode 0)
			)
			(polygon
				(pts
					(xy 78.598268 -125.3871) (xy 79.106268 -125.3871) (xy 79.106268 -126.3777) (xy 78.598268 -126.3777)
				)
			)
		)
		(zone
			(layer "B.Cu")
			(hatch none 0.5)
			(connect_pads
				(clearance 0)
			)
			(min_thickness 0.25)
			(keepout
				(tracks allowed)
				(vias not_allowed)
				(pads allowed)
				(copperpour not_allowed)
				(footprints allowed)
			)
			(placement
				(enabled no)
				(sheetname "")
			)
			(fill
				(thermal_gap 0.5)
				(thermal_bridge_width 0.5)
				(island_removal_mode 0)
			)
			(polygon
				(pts
					(xy 78.598268 -125.3871) (xy 79.106268 -125.3871) (xy 79.106268 -126.3777) (xy 78.598268 -126.3777)
				)
			)
		)
	)
)
